(kicad_pcb
	(version 20260206)
	(generator "pcbnew")
	(generator_version "10.0")
	(general
		(thickness 1.6)
		(legacy_teardrops no)
	)
	(paper "A4")
	(title_block
		(title "01162023_DA0F0TEBIF0_F0T_Expander_BD_F_brd_V02_OCP.brd")
		(comment 1 "Grand Teton / footprints 269-274 of 9728")
	)
	(layers
		(0 "F.Cu" signal "TOP")
		(4 "In1.Cu" signal "GND")
		(6 "In2.Cu" signal "VCC")
		(8 "In3.Cu" signal "VCC1")
		(10 "In4.Cu" signal "GND1")
		(12 "In5.Cu" signal "IN1")
		(14 "In6.Cu" signal "GND2")
		(16 "In7.Cu" signal "IN2")
		(18 "In8.Cu" signal "GND3")
		(20 "In9.Cu" signal "IN3")
		(22 "In10.Cu" signal "GND4")
		(24 "In11.Cu" signal "IN4")
		(26 "In12.Cu" signal "GND5")
		(28 "In13.Cu" signal "IN5")
		(30 "In14.Cu" signal "GND6")
		(32 "In15.Cu" signal "IN6")
		(34 "In16.Cu" signal "GND7")
		(2 "B.Cu" signal "BOTTOM")
		(9 "F.Adhes" user "F.Adhesive")
		(11 "B.Adhes" user "B.Adhesive")
		(13 "F.Paste" user "Package Geometry/Pastemask Top")
		(15 "B.Paste" user "Package Geometry/Pastemask Bottom")
		(5 "F.SilkS" user "Ref Des/Silkscreen Top")
		(7 "B.SilkS" user "Ref Des/Silkscreen Bottom")
		(1 "F.Mask" user "Board Geometry/Soldermask Top")
		(3 "B.Mask" user "Board Geometry/Soldermask Bottom")
		(17 "Dwgs.User" user "User.Drawings")
		(19 "Cmts.User" user "User.Comments")
		(21 "Eco1.User" user "User.Eco1")
		(23 "Eco2.User" user "User.Eco2")
		(25 "Edge.Cuts" user "Board Geometry/Outline")
		(27 "Margin" user)
		(31 "F.CrtYd" user "Package Geometry/Place Bound Top")
		(29 "B.CrtYd" user "Package Geometry/Place Bound Bottom")
		(35 "F.Fab" user "Ref Des/Assembly Top")
		(33 "B.Fab" user "Ref Des/Assembly Bottom")
	)
	(footprint ""
		(layer "F.Cu")
		(at 356.479094 -59.577986 -90)
		(property "Reference" "R895"
			(at 0 0 270)
			(layer "F.SilkS")
			(hide yes)
			(effects
				(font
					(size 1.27 1.27)
				)
			)
		)
		(property "Value" ""
			(at 0 0 270)
			(layer "F.Fab")
			(effects
				(font
					(size 1.27 1.27)
				)
			)
		)
		(duplicate_pad_numbers_are_jumpers no)
		(fp_line
			(start -0.7874 0.4064)
			(end -0.7874 -0.4064)
			(stroke
				(width 0.1524)
				(type default)
			)
			(layer "F.SilkS")
		)
		(fp_line
			(start 0.7874 0.4064)
			(end -0.7874 0.4064)
			(stroke
				(width 0.1524)
				(type default)
			)
			(layer "F.SilkS")
		)
		(fp_line
			(start -0.7874 -0.4064)
			(end 0.7874 -0.4064)
			(stroke
				(width 0.1524)
				(type default)
			)
			(layer "F.SilkS")
		)
		(fp_line
			(start 0.7874 -0.4064)
			(end 0.7874 0.4064)
			(stroke
				(width 0.1524)
				(type default)
			)
			(layer "F.SilkS")
		)
		(fp_line
			(start -0.67945 0.3048)
			(end -0.67945 -0.305054)
			(stroke
				(width 0.1)
				(type default)
			)
			(layer "F.Fab")
		)
		(fp_line
			(start -0.12065 0.3048)
			(end -0.67945 0.3048)
			(stroke
				(width 0.1)
				(type default)
			)
			(layer "F.Fab")
		)
		(fp_line
			(start 0.120396 0.3048)
			(end 0.120396 0.2794)
			(stroke
				(width 0.1)
				(type default)
			)
			(layer "F.Fab")
		)
		(fp_line
			(start 0.67945 0.3048)
			(end 0.120396 0.3048)
			(stroke
				(width 0.1)
				(type default)
			)
			(layer "F.Fab")
		)
		(fp_line
			(start -0.12065 0.2794)
			(end -0.12065 0.3048)
			(stroke
				(width 0.1)
				(type default)
			)
			(layer "F.Fab")
		)
		(fp_line
			(start 0.120396 0.2794)
			(end -0.12065 0.2794)
			(stroke
				(width 0.1)
				(type default)
			)
			(layer "F.Fab")
		)
		(fp_line
			(start -0.12065 -0.2794)
			(end 0.12065 -0.2794)
			(stroke
				(width 0.1)
				(type default)
			)
			(layer "F.Fab")
		)
		(fp_line
			(start 0.12065 -0.2794)
			(end 0.12065 -0.3048)
			(stroke
				(width 0.1)
				(type default)
			)
			(layer "F.Fab")
		)
		(fp_line
			(start 0.12065 -0.3048)
			(end 0.67945 -0.3048)
			(stroke
				(width 0.1)
				(type default)
			)
			(layer "F.Fab")
		)
		(fp_line
			(start 0.67945 -0.3048)
			(end 0.67945 0.3048)
			(stroke
				(width 0.1)
				(type default)
			)
			(layer "F.Fab")
		)
		(fp_line
			(start -0.67945 -0.305054)
			(end -0.12065 -0.305054)
			(stroke
				(width 0.1)
				(type default)
			)
			(layer "F.Fab")
		)
		(fp_line
			(start -0.12065 -0.305054)
			(end -0.12065 -0.2794)
			(stroke
				(width 0.1)
				(type default)
			)
			(layer "F.Fab")
		)
		(pad "1" smd circle
			(at -0.40005 0 270)
			(size 0 0)
			(layers "F.Cu" "F.Mask" "F.Paste")
			(net "P3V3_SSD12")
		)
		(pad "2" smd circle
			(at 0.40005 0 270)
			(size 0 0)
			(layers "F.Cu" "F.Mask" "F.Paste")
			(net "PWRGD_P3V3_SSD12")
		)
	)
	(footprint ""
		(layer "F.Cu")
		(at 239.260126 -51.89728 90)
		(property "Reference" "PU62"
			(at -1.509014 3.019552 90)
			(unlocked yes)
			(layer "F.SilkS")
			(effects
				(font
					(size 0.7874 0.5842)
					(thickness 0.1524)
				)
				(justify left)
			)
		)
		(property "Value" ""
			(at 0 0 90)
			(layer "F.Fab")
			(effects
				(font
					(size 1.27 1.27)
				)
			)
		)
		(duplicate_pad_numbers_are_jumpers no)
		(fp_line
			(start 1.943608 -1.549908)
			(end 1.943608 1.549908)
			(stroke
				(width 0.1524)
				(type default)
			)
			(layer "F.SilkS")
		)
		(fp_line
			(start -1.943608 -1.549908)
			(end 1.943608 -1.549908)
			(stroke
				(width 0.1524)
				(type default)
			)
			(layer "F.SilkS")
		)
		(fp_line
			(start 1.943608 1.549908)
			(end -1.943608 1.549908)
			(stroke
				(width 0.1524)
				(type default)
			)
			(layer "F.SilkS")
		)
		(fp_line
			(start -1.943608 1.549908)
			(end -1.943608 -1.549908)
			(stroke
				(width 0.1524)
				(type default)
			)
			(layer "F.SilkS")
		)
		(fp_poly
			(pts
				(xy -2.019808 -1.549908) (xy -1.257808 -1.549908) (xy -1.257808 -1.880108) (xy -2.019808 -1.880108)
			)
			(stroke
				(width 0)
				(type default)
			)
			(fill yes)
			(layer "F.SilkS")
		)
		(fp_line
			(start 1.549908 -1.549908)
			(end 1.549908 1.549908)
			(stroke
				(width 0.1)
				(type default)
			)
			(layer "F.Fab")
		)
		(fp_line
			(start -1.549908 -1.549908)
			(end 1.549908 -1.549908)
			(stroke
				(width 0.1)
				(type default)
			)
			(layer "F.Fab")
		)
		(fp_line
			(start 1.549908 1.549908)
			(end -1.549908 1.549908)
			(stroke
				(width 0.1)
				(type default)
			)
			(layer "F.Fab")
		)
		(fp_line
			(start -1.549908 1.549908)
			(end -1.549908 -1.549908)
			(stroke
				(width 0.1)
				(type default)
			)
			(layer "F.Fab")
		)
		(fp_poly
			(pts
				(xy -2.019808 -1.549908) (xy -1.257808 -1.549908) (xy -1.257808 -1.880108) (xy -2.019808 -1.880108)
			)
			(stroke
				(width 0)
				(type default)
			)
			(fill yes)
			(layer "F.Fab")
		)
		(pad "1" smd rect
			(at -1.500124 -1.249934)
			(size 0.2794 0.6096)
			(layers "F.Cu" "F.Mask" "F.Paste")
			(net "P3V3_SSD8")
		)
		(pad "2" smd rect
			(at -1.500124 -0.750062)
			(size 0.2794 0.6096)
			(layers "F.Cu" "F.Mask" "F.Paste")
			(net "P3V3_SSD8")
		)
		(pad "3" smd rect
			(at -1.500124 -0.249936)
			(size 0.2794 0.6096)
			(layers "F.Cu" "F.Mask" "F.Paste")
			(net "P3V3_SSD8")
		)
		(pad "4" smd rect
			(at -1.500124 0.249936)
			(size 0.2794 0.6096)
			(layers "F.Cu" "F.Mask" "F.Paste")
			(net "P3V3_SSD8")
		)
		(pad "5" smd rect
			(at -1.500124 0.750062)
			(size 0.2794 0.6096)
			(layers "F.Cu" "F.Mask" "F.Paste")
			(net "P3V3_SSD8")
		)
		(pad "6" smd rect
			(at -1.500124 1.249934)
			(size 0.2794 0.6096)
			(layers "F.Cu" "F.Mask" "F.Paste")
			(net "GND")
		)
		(pad "7" smd rect
			(at 1.500124 1.249934)
			(size 0.2794 0.6096)
			(layers "F.Cu" "F.Mask" "F.Paste")
			(net "P3V3_SSD8_SS")
		)
		(pad "8" smd rect
			(at 1.500124 0.750062)
			(size 0.2794 0.6096)
			(layers "F.Cu" "F.Mask" "F.Paste")
			(net "PWRGD_P3V3_SSD8")
		)
		(pad "9" smd rect
			(at 1.500124 0.249936)
			(size 0.2794 0.6096)
			(layers "F.Cu" "F.Mask" "F.Paste")
			(net "P3V3_SSD8_OCP")
		)
		(pad "10" smd rect
			(at 1.500124 -0.249936)
			(size 0.2794 0.6096)
			(layers "F.Cu" "F.Mask" "F.Paste")
			(net "P5V_AUX")
		)
		(pad "11" smd rect
			(at 1.500124 -0.750062)
			(size 0.2794 0.6096)
			(layers "F.Cu" "F.Mask" "F.Paste")
			(net "SSD8_AUX_P3V3_EN_R")
		)
		(pad "12" smd rect
			(at 1.500124 -1.249934)
			(size 0.2794 0.6096)
			(layers "F.Cu" "F.Mask" "F.Paste")
			(net "P3V3_AUX")
		)
		(pad "13" smd rect
			(at 0 0 90)
			(size 1.9812 2.7178)
			(layers "F.Cu" "F.Mask" "F.Paste")
			(net "P3V3_AUX")
		)
		(zone
			(layer "F.Cu")
			(hatch none 0.5)
			(connect_pads
				(clearance 0)
			)
			(min_thickness 0.25)
			(keepout
				(tracks not_allowed)
				(vias allowed)
				(pads allowed)
				(copperpour not_allowed)
				(footprints allowed)
			)
			(placement
				(enabled no)
				(sheetname "")
			)
			(fill
				(thermal_gap 0.5)
				(thermal_bridge_width 0.5)
				(island_removal_mode 0)
			)
			(polygon
				(pts
					(xy 237.710726 -53.04028) (xy 237.837726 -53.04028) (xy 240.809526 -53.04028) (xy 240.810034 -53.04028)
					(xy 240.810034 -50.75428) (xy 240.809526 -50.75428) (xy 240.682526 -50.75428) (xy 239.260126 -50.75428)
					(xy 239.260126 -50.85588) (xy 240.682526 -50.85588) (xy 240.682526 -52.93868) (xy 237.837726 -52.93868)
					(xy 237.837726 -50.85588) (xy 239.234726 -50.85588) (xy 239.234726 -50.75428) (xy 237.837726 -50.75428)
					(xy 237.710726 -50.75428) (xy 237.710218 -50.75428) (xy 237.710218 -53.04028)
				)
			)
		)
	)
	(footprint ""
		(layer "F.Cu")
		(at 238.742474 -257.975862 -90)
		(property "Reference" "R6523"
			(at 0 0 270)
			(layer "F.SilkS")
			(hide yes)
			(effects
				(font
					(size 1.27 1.27)
				)
			)
		)
		(property "Value" ""
			(at 0 0 270)
			(layer "F.Fab")
			(effects
				(font
					(size 1.27 1.27)
				)
			)
		)
		(duplicate_pad_numbers_are_jumpers no)
		(fp_line
			(start -0.7874 0.4064)
			(end -0.7874 -0.4064)
			(stroke
				(width 0.1524)
				(type default)
			)
			(layer "F.SilkS")
		)
		(fp_line
			(start 0.7874 0.4064)
			(end -0.7874 0.4064)
			(stroke
				(width 0.1524)
				(type default)
			)
			(layer "F.SilkS")
		)
		(fp_line
			(start -0.7874 -0.4064)
			(end 0.7874 -0.4064)
			(stroke
				(width 0.1524)
				(type default)
			)
			(layer "F.SilkS")
		)
		(fp_line
			(start 0.7874 -0.4064)
			(end 0.7874 0.4064)
			(stroke
				(width 0.1524)
				(type default)
			)
			(layer "F.SilkS")
		)
		(fp_line
			(start -0.67945 0.3048)
			(end -0.67945 -0.305054)
			(stroke
				(width 0.1)
				(type default)
			)
			(layer "F.Fab")
		)
		(fp_line
			(start -0.12065 0.3048)
			(end -0.67945 0.3048)
			(stroke
				(width 0.1)
				(type default)
			)
			(layer "F.Fab")
		)
		(fp_line
			(start 0.120396 0.3048)
			(end 0.120396 0.2794)
			(stroke
				(width 0.1)
				(type default)
			)
			(layer "F.Fab")
		)
		(fp_line
			(start 0.67945 0.3048)
			(end 0.120396 0.3048)
			(stroke
				(width 0.1)
				(type default)
			)
			(layer "F.Fab")
		)
		(fp_line
			(start -0.12065 0.2794)
			(end -0.12065 0.3048)
			(stroke
				(width 0.1)
				(type default)
			)
			(layer "F.Fab")
		)
		(fp_line
			(start 0.120396 0.2794)
			(end -0.12065 0.2794)
			(stroke
				(width 0.1)
				(type default)
			)
			(layer "F.Fab")
		)
		(fp_line
			(start -0.12065 -0.2794)
			(end 0.12065 -0.2794)
			(stroke
				(width 0.1)
				(type default)
			)
			(layer "F.Fab")
		)
		(fp_line
			(start 0.12065 -0.2794)
			(end 0.12065 -0.3048)
			(stroke
				(width 0.1)
				(type default)
			)
			(layer "F.Fab")
		)
		(fp_line
			(start 0.12065 -0.3048)
			(end 0.67945 -0.3048)
			(stroke
				(width 0.1)
				(type default)
			)
			(layer "F.Fab")
		)
		(fp_line
			(start 0.67945 -0.3048)
			(end 0.67945 0.3048)
			(stroke
				(width 0.1)
				(type default)
			)
			(layer "F.Fab")
		)
		(fp_line
			(start -0.67945 -0.305054)
			(end -0.12065 -0.305054)
			(stroke
				(width 0.1)
				(type default)
			)
			(layer "F.Fab")
		)
		(fp_line
			(start -0.12065 -0.305054)
			(end -0.12065 -0.2794)
			(stroke
				(width 0.1)
				(type default)
			)
			(layer "F.Fab")
		)
		(pad "1" smd circle
			(at -0.40005 0 270)
			(size 0 0)
			(layers "F.Cu" "F.Mask" "F.Paste")
			(net "P1V25_SERDES_VDDPLL_PEX2")
		)
		(pad "2" smd circle
			(at 0.40005 0 270)
			(size 0 0)
			(layers "F.Cu" "F.Mask" "F.Paste")
			(net "P1V25_SERDES_VDDPLL_PEX2_C2")
		)
	)
	(footprint ""
		(layer "F.Cu")
		(at 138.508486 -257.102102)
		(property "Reference" "Q14"
			(at -3.74142 -0.768604 0)
			(unlocked yes)
			(layer "F.SilkS")
			(effects
				(font
					(size 0.7874 0.5842)
					(thickness 0.1524)
				)
			)
		)
		(property "Value" ""
			(at 0 0 0)
			(layer "F.Fab")
			(effects
				(font
					(size 1.27 1.27)
				)
			)
		)
		(duplicate_pad_numbers_are_jumpers no)
		(fp_line
			(start -1.376172 -1.199896)
			(end -0.508 -1.199896)
			(stroke
				(width 0.1524)
				(type default)
			)
			(layer "F.SilkS")
		)
		(fp_line
			(start -1.376172 1.199896)
			(end -1.376172 -1.199896)
			(stroke
				(width 0.1524)
				(type default)
			)
			(layer "F.SilkS")
		)
		(fp_line
			(start -0.508 -1.199896)
			(end 0 -0.762)
			(stroke
				(width 0.1524)
				(type default)
			)
			(layer "F.SilkS")
		)
		(fp_line
			(start 0 -0.762)
			(end 0.508 -1.199896)
			(stroke
				(width 0.1524)
				(type default)
			)
			(layer "F.SilkS")
		)
		(fp_line
			(start 0.508 -1.199896)
			(end 1.376172 -1.199896)
			(stroke
				(width 0.1524)
				(type default)
			)
			(layer "F.SilkS")
		)
		(fp_line
			(start 1.376172 -1.199896)
			(end 1.376172 1.199896)
			(stroke
				(width 0.1524)
				(type default)
			)
			(layer "F.SilkS")
		)
		(fp_line
			(start 1.376172 1.199896)
			(end -1.376172 1.199896)
			(stroke
				(width 0.1524)
				(type default)
			)
			(layer "F.SilkS")
		)
		(fp_poly
			(pts
				(xy -1.4605 -0.7493) (xy -2.2225 -1.1303) (xy -2.2225 -0.3683)
			)
			(stroke
				(width 0)
				(type default)
			)
			(fill yes)
			(layer "F.SilkS")
		)
		(fp_line
			(start -0.674878 -1.100074)
			(end 0.674878 -1.100074)
			(stroke
				(width 0.1)
				(type default)
			)
			(layer "F.Fab")
		)
		(fp_line
			(start -0.674878 1.100074)
			(end -0.674878 -1.100074)
			(stroke
				(width 0.1)
				(type default)
			)
			(layer "F.Fab")
		)
		(fp_line
			(start 0.674878 -1.100074)
			(end 0.674878 1.100074)
			(stroke
				(width 0.1)
				(type default)
			)
			(layer "F.Fab")
		)
		(fp_line
			(start 0.674878 1.100074)
			(end -0.674878 1.100074)
			(stroke
				(width 0.1)
				(type default)
			)
			(layer "F.Fab")
		)
		(fp_poly
			(pts
				(xy -1.4605 -0.7493) (xy -2.2225 -1.1303) (xy -2.2225 -0.3683)
			)
			(stroke
				(width 0)
				(type default)
			)
			(fill yes)
			(layer "F.Fab")
		)
		(pad "1" smd rect
			(at -0.899922 -0.750062 270)
			(size 0.6096 0.6096)
			(layers "F.Cu" "F.Mask" "F.Paste")
			(net "GND")
		)
		(pad "2" smd rect
			(at -0.899922 0 270)
			(size 0.4064 0.6096)
			(layers "F.Cu" "F.Mask" "F.Paste")
			(net "PEX1_SYS_ERR_R_N")
		)
		(pad "3" smd rect
			(at -0.899922 0.750062 270)
			(size 0.6096 0.6096)
			(layers "F.Cu" "F.Mask" "F.Paste")
			(net "PEX1_SYS_ERR_3V3_N")
		)
		(pad "4" smd rect
			(at 0.899922 0.750062 270)
			(size 0.6096 0.6096)
			(layers "F.Cu" "F.Mask" "F.Paste")
			(net "GND")
		)
		(pad "5" smd rect
			(at 0.899922 0 270)
			(size 0.4064 0.6096)
			(layers "F.Cu" "F.Mask" "F.Paste")
			(net "PEX1_SYS_ERR_N_G")
		)
		(pad "6" smd rect
			(at 0.899922 -0.750062 270)
			(size 0.6096 0.6096)
			(layers "F.Cu" "F.Mask" "F.Paste")
			(net "PEX1_SYS_ERR_N_G")
		)
	)
	(footprint ""
		(layer "F.Cu")
		(at 350.888554 -277.639272 180)
		(property "Reference" "PC190"
			(at 0 0 180)
			(layer "F.SilkS")
			(hide yes)
			(effects
				(font
					(size 1.27 1.27)
				)
			)
		)
		(property "Value" ""
			(at 0 0 180)
			(layer "F.Fab")
			(effects
				(font
					(size 1.27 1.27)
				)
			)
		)
		(duplicate_pad_numbers_are_jumpers no)
		(fp_line
			(start 1.524 0.762)
			(end -1.524 0.762)
			(stroke
				(width 0.1524)
				(type default)
			)
			(layer "F.SilkS")
		)
		(fp_line
			(start 1.524 -0.762)
			(end 1.524 0.762)
			(stroke
				(width 0.1524)
				(type default)
			)
			(layer "F.SilkS")
		)
		(fp_line
			(start -1.524 0.762)
			(end -1.524 -0.762)
			(stroke
				(width 0.1524)
				(type default)
			)
			(layer "F.SilkS")
		)
		(fp_line
			(start -1.524 -0.762)
			(end 1.524 -0.762)
			(stroke
				(width 0.1524)
				(type default)
			)
			(layer "F.SilkS")
		)
		(fp_line
			(start 1.1049 0.724916)
			(end 1.1049 -0.724916)
			(stroke
				(width 0.1)
				(type default)
			)
			(layer "F.Fab")
		)
		(fp_line
			(start 1.1049 -0.724916)
			(end -1.1049 -0.724916)
			(stroke
				(width 0.1)
				(type default)
			)
			(layer "F.Fab")
		)
		(fp_line
			(start -1.1049 0.724916)
			(end 1.1049 0.724916)
			(stroke
				(width 0.1)
				(type default)
			)
			(layer "F.Fab")
		)
		(fp_line
			(start -1.1049 -0.724916)
			(end -1.1049 0.724916)
			(stroke
				(width 0.1)
				(type default)
			)
			(layer "F.Fab")
		)
		(pad "1" smd rect
			(at -0.889 0)
			(size 1.016 1.27)
			(layers "F.Cu" "F.Mask" "F.Paste")
			(net "SW_P12V_P0V8_PEX3_FLT")
		)
		(pad "2" smd rect
			(at 0.889 0)
			(size 1.016 1.27)
			(layers "F.Cu" "F.Mask" "F.Paste")
			(net "GND")
		)
	)
	(footprint ""
		(layer "F.Cu")
		(at 280.137616 -405.074374 -90)
		(property "Reference" "R1816"
			(at 0 0 270)
			(layer "F.SilkS")
			(hide yes)
			(effects
				(font
					(size 1.27 1.27)
				)
			)
		)
		(property "Value" ""
			(at 0 0 270)
			(layer "F.Fab")
			(effects
				(font
					(size 1.27 1.27)
				)
			)
		)
		(duplicate_pad_numbers_are_jumpers no)
		(fp_line
			(start -0.7874 0.4064)
			(end -0.7874 -0.4064)
			(stroke
				(width 0.1524)
				(type default)
			)
			(layer "F.SilkS")
		)
		(fp_line
			(start 0.7874 0.4064)
			(end -0.7874 0.4064)
			(stroke
				(width 0.1524)
				(type default)
			)
			(layer "F.SilkS")
		)
		(fp_line
			(start -0.7874 -0.4064)
			(end 0.7874 -0.4064)
			(stroke
				(width 0.1524)
				(type default)
			)
			(layer "F.SilkS")
		)
		(fp_line
			(start 0.7874 -0.4064)
			(end 0.7874 0.4064)
			(stroke
				(width 0.1524)
				(type default)
			)
			(layer "F.SilkS")
		)
		(fp_line
			(start -0.67945 0.3048)
			(end -0.67945 -0.305054)
			(stroke
				(width 0.1)
				(type default)
			)
			(layer "F.Fab")
		)
		(fp_line
			(start -0.12065 0.3048)
			(end -0.67945 0.3048)
			(stroke
				(width 0.1)
				(type default)
			)
			(layer "F.Fab")
		)
		(fp_line
			(start 0.120396 0.3048)
			(end 0.120396 0.2794)
			(stroke
				(width 0.1)
				(type default)
			)
			(layer "F.Fab")
		)
		(fp_line
			(start 0.67945 0.3048)
			(end 0.120396 0.3048)
			(stroke
				(width 0.1)
				(type default)
			)
			(layer "F.Fab")
		)
		(fp_line
			(start -0.12065 0.2794)
			(end -0.12065 0.3048)
			(stroke
				(width 0.1)
				(type default)
			)
			(layer "F.Fab")
		)
		(fp_line
			(start 0.120396 0.2794)
			(end -0.12065 0.2794)
			(stroke
				(width 0.1)
				(type default)
			)
			(layer "F.Fab")
		)
		(fp_line
			(start -0.12065 -0.2794)
			(end 0.12065 -0.2794)
			(stroke
				(width 0.1)
				(type default)
			)
			(layer "F.Fab")
		)
		(fp_line
			(start 0.12065 -0.2794)
			(end 0.12065 -0.3048)
			(stroke
				(width 0.1)
				(type default)
			)
			(layer "F.Fab")
		)
		(fp_line
			(start 0.12065 -0.3048)
			(end 0.67945 -0.3048)
			(stroke
				(width 0.1)
				(type default)
			)
			(layer "F.Fab")
		)
		(fp_line
			(start 0.67945 -0.3048)
			(end 0.67945 0.3048)
			(stroke
				(width 0.1)
				(type default)
			)
			(layer "F.Fab")
		)
		(fp_line
			(start -0.67945 -0.305054)
			(end -0.12065 -0.305054)
			(stroke
				(width 0.1)
				(type default)
			)
			(layer "F.Fab")
		)
		(fp_line
			(start -0.12065 -0.305054)
			(end -0.12065 -0.2794)
			(stroke
				(width 0.1)
				(type default)
			)
			(layer "F.Fab")
		)
		(pad "1" smd circle
			(at -0.40005 0 270)
			(size 0 0)
			(layers "F.Cu" "F.Mask" "F.Paste")
			(net "MB_BIC_MON_BUF")
		)
		(pad "2" smd circle
			(at 0.40005 0 270)
			(size 0 0)
			(layers "F.Cu" "F.Mask" "F.Paste")
			(net "MB_BIC_MON_BUF_R")
		)
	)
)
